# SCM (Grand Teton) — schematic netlist excerpt (pin names and nets, part order shuffled) for the footprints in the layout excerpt that follows; sources: Cadence DE-HDL packaged netlist, KiCad conversion of 12092022_DA0F0TMDCD0_F0T_Management_Board_D_brd_V3_OCP.brd

R508  Q_RES  10K 1% CHIP  pkg 0402LF  page 48 : A = P3V3_AUX ; B = MB_JTAG_PLD_R_JTAGEN
H2B1  HOLE  EMPTY  pkg TH  page 57 : \1\ = NC
C500  Q_CAP  0.1UF 25V 10% X7R  pkg 0402  page 31 : A = P3V3_AUX ; B = GND

(kicad_pcb
	(version 20260206)
	(generator "pcbnew")
	(generator_version "10.0")
	(general
		(thickness 1.6)
		(legacy_teardrops no)
	)
	(paper "A4")
	(title_block
		(title "12092022_DA0F0TMDCD0_F0T_Management_Board_D_brd_V3_OCP.brd")
		(comment 1 "Grand Teton / footprints 517-519 of 1440")
	)
	(layers
		(0 "F.Cu" signal "TOP")
		(4 "In1.Cu" signal "GND")
		(6 "In2.Cu" signal "IN1")
		(8 "In3.Cu" signal "GND1")
		(10 "In4.Cu" signal "IN2")
		(12 "In5.Cu" signal "VCC")
		(14 "In6.Cu" signal "VCC1")
		(16 "In7.Cu" signal "IN3")
		(18 "In8.Cu" signal "GND2")
		(20 "In9.Cu" signal "IN4")
		(22 "In10.Cu" signal "GND3")
		(2 "B.Cu" signal "BOTTOM")
		(9 "F.Adhes" user "F.Adhesive")
		(11 "B.Adhes" user "B.Adhesive")
		(13 "F.Paste" user "Package Geometry/Pastemask Top")
		(15 "B.Paste" user "Package Geometry/Pastemask Bottom")
		(5 "F.SilkS" user "Ref Des/Silkscreen Top")
		(7 "B.SilkS" user "Ref Des/Silkscreen Bottom")
		(1 "F.Mask" user "Board Geometry/Soldermask Top")
		(3 "B.Mask" user "Board Geometry/Soldermask Bottom")
		(17 "Dwgs.User" user "User.Drawings")
		(19 "Cmts.User" user "User.Comments")
		(21 "Eco1.User" user "User.Eco1")
		(23 "Eco2.User" user "User.Eco2")
		(25 "Edge.Cuts" user "Board Geometry/Outline")
		(27 "Margin" user)
		(31 "F.CrtYd" user "Package Geometry/Place Bound Top")
		(29 "B.CrtYd" user "Package Geometry/Place Bound Bottom")
		(35 "F.Fab" user "Ref Des/Assembly Top")
		(33 "B.Fab" user "Ref Des/Assembly Bottom")
	)
	(footprint ""
		(layer "F.Cu")
		(at 21.971 -66.1162 90)
		(property "Reference" "C500"
			(at 0 0 90)
			(layer "F.SilkS")
			(hide yes)
			(effects
				(font
					(size 1.27 1.27)
				)
			)
		)
		(property "Value" ""
			(at 0 0 90)
			(layer "F.Fab")
			(effects
				(font
					(size 1.27 1.27)
				)
			)
		)
		(duplicate_pad_numbers_are_jumpers no)
		(fp_line
			(start 0.7874 -0.4064)
			(end 0.7874 0.4064)
			(stroke
				(width 0.1524)
				(type default)
			)
			(layer "F.SilkS")
		)
		(fp_line
			(start -0.7874 -0.4064)
			(end 0.7874 -0.4064)
			(stroke
				(width 0.1524)
				(type default)
			)
			(layer "F.SilkS")
		)
		(fp_line
			(start 0.7874 0.4064)
			(end -0.7874 0.4064)
			(stroke
				(width 0.1524)
				(type default)
			)
			(layer "F.SilkS")
		)
		(fp_line
			(start -0.7874 0.4064)
			(end -0.7874 -0.4064)
			(stroke
				(width 0.1524)
				(type default)
			)
			(layer "F.SilkS")
		)
		(fp_line
			(start -0.12065 -0.305054)
			(end -0.12065 -0.2794)
			(stroke
				(width 0.1)
				(type default)
			)
			(layer "F.Fab")
		)
		(fp_line
			(start -0.67945 -0.305054)
			(end -0.12065 -0.305054)
			(stroke
				(width 0.1)
				(type default)
			)
			(layer "F.Fab")
		)
		(fp_line
			(start 0.67945 -0.3048)
			(end 0.67945 0.3048)
			(stroke
				(width 0.1)
				(type default)
			)
			(layer "F.Fab")
		)
		(fp_line
			(start 0.12065 -0.3048)
			(end 0.67945 -0.3048)
			(stroke
				(width 0.1)
				(type default)
			)
			(layer "F.Fab")
		)
		(fp_line
			(start 0.12065 -0.2794)
			(end 0.12065 -0.3048)
			(stroke
				(width 0.1)
				(type default)
			)
			(layer "F.Fab")
		)
		(fp_line
			(start -0.12065 -0.2794)
			(end 0.12065 -0.2794)
			(stroke
				(width 0.1)
				(type default)
			)
			(layer "F.Fab")
		)
		(fp_line
			(start 0.120396 0.2794)
			(end -0.12065 0.2794)
			(stroke
				(width 0.1)
				(type default)
			)
			(layer "F.Fab")
		)
		(fp_line
			(start -0.12065 0.2794)
			(end -0.12065 0.3048)
			(stroke
				(width 0.1)
				(type default)
			)
			(layer "F.Fab")
		)
		(fp_line
			(start 0.67945 0.3048)
			(end 0.120396 0.3048)
			(stroke
				(width 0.1)
				(type default)
			)
			(layer "F.Fab")
		)
		(fp_line
			(start 0.120396 0.3048)
			(end 0.120396 0.2794)
			(stroke
				(width 0.1)
				(type default)
			)
			(layer "F.Fab")
		)
		(fp_line
			(start -0.12065 0.3048)
			(end -0.67945 0.3048)
			(stroke
				(width 0.1)
				(type default)
			)
			(layer "F.Fab")
		)
		(fp_line
			(start -0.67945 0.3048)
			(end -0.67945 -0.305054)
			(stroke
				(width 0.1)
				(type default)
			)
			(layer "F.Fab")
		)
		(pad "1" smd circle
			(at -0.40005 0 90)
			(size 0 0)
			(layers "F.Cu" "F.Mask" "F.Paste")
			(net "P3V3_AUX")
		)
		(pad "2" smd circle
			(at 0.40005 0 90)
			(size 0 0)
			(layers "F.Cu" "F.Mask" "F.Paste")
			(net "GND")
		)
	)
	(footprint ""
		(layer "F.Cu")
		(at 61.469016 -81.10474)
		(property "Reference" "R508"
			(at 0 0 0)
			(layer "F.SilkS")
			(hide yes)
			(effects
				(font
					(size 1.27 1.27)
				)
			)
		)
		(property "Value" ""
			(at 0 0 0)
			(layer "F.Fab")
			(effects
				(font
					(size 1.27 1.27)
				)
			)
		)
		(duplicate_pad_numbers_are_jumpers no)
		(fp_line
			(start -0.7874 -0.4064)
			(end 0.7874 -0.4064)
			(stroke
				(width 0.1524)
				(type default)
			)
			(layer "F.SilkS")
		)
		(fp_line
			(start -0.7874 0.4064)
			(end -0.7874 -0.4064)
			(stroke
				(width 0.1524)
				(type default)
			)
			(layer "F.SilkS")
		)
		(fp_line
			(start 0.7874 -0.4064)
			(end 0.7874 0.4064)
			(stroke
				(width 0.1524)
				(type default)
			)
			(layer "F.SilkS")
		)
		(fp_line
			(start 0.7874 0.4064)
			(end -0.7874 0.4064)
			(stroke
				(width 0.1524)
				(type default)
			)
			(layer "F.SilkS")
		)
		(fp_line
			(start -0.67945 -0.305054)
			(end -0.12065 -0.305054)
			(stroke
				(width 0.1)
				(type default)
			)
			(layer "F.Fab")
		)
		(fp_line
			(start -0.67945 0.3048)
			(end -0.67945 -0.305054)
			(stroke
				(width 0.1)
				(type default)
			)
			(layer "F.Fab")
		)
		(fp_line
			(start -0.12065 -0.305054)
			(end -0.12065 -0.2794)
			(stroke
				(width 0.1)
				(type default)
			)
			(layer "F.Fab")
		)
		(fp_line
			(start -0.12065 -0.2794)
			(end 0.12065 -0.2794)
			(stroke
				(width 0.1)
				(type default)
			)
			(layer "F.Fab")
		)
		(fp_line
			(start -0.12065 0.2794)
			(end -0.12065 0.3048)
			(stroke
				(width 0.1)
				(type default)
			)
			(layer "F.Fab")
		)
		(fp_line
			(start -0.12065 0.3048)
			(end -0.67945 0.3048)
			(stroke
				(width 0.1)
				(type default)
			)
			(layer "F.Fab")
		)
		(fp_line
			(start 0.120396 0.2794)
			(end -0.12065 0.2794)
			(stroke
				(width 0.1)
				(type default)
			)
			(layer "F.Fab")
		)
		(fp_line
			(start 0.120396 0.3048)
			(end 0.120396 0.2794)
			(stroke
				(width 0.1)
				(type default)
			)
			(layer "F.Fab")
		)
		(fp_line
			(start 0.12065 -0.3048)
			(end 0.67945 -0.3048)
			(stroke
				(width 0.1)
				(type default)
			)
			(layer "F.Fab")
		)
		(fp_line
			(start 0.12065 -0.2794)
			(end 0.12065 -0.3048)
			(stroke
				(width 0.1)
				(type default)
			)
			(layer "F.Fab")
		)
		(fp_line
			(start 0.67945 -0.3048)
			(end 0.67945 0.3048)
			(stroke
				(width 0.1)
				(type default)
			)
			(layer "F.Fab")
		)
		(fp_line
			(start 0.67945 0.3048)
			(end 0.120396 0.3048)
			(stroke
				(width 0.1)
				(type default)
			)
			(layer "F.Fab")
		)
		(pad "1" smd circle
			(at -0.40005 0)
			(size 0 0)
			(layers "F.Cu" "F.Mask" "F.Paste")
			(net "P3V3_AUX")
		)
		(pad "2" smd circle
			(at 0.40005 0)
			(size 0 0)
			(layers "F.Cu" "F.Mask" "F.Paste")
			(net "MB_JTAG_PLD_R_JTAGEN")
		)
	)
	(footprint ""
		(layer "F.Cu")
		(at 86.522306 -109.933486 90)
		(property "Reference" "H2B1"
			(at -3.102356 -3.769106 0)
			(unlocked yes)
			(layer "F.SilkS")
			(effects
				(font
					(size 0.7874 0.5842)
					(thickness 0.1524)
				)
				(justify left)
			)
		)
		(property "Value" ""
			(at 0 0 90)
			(layer "F.Fab")
			(effects
				(font
					(size 1.27 1.27)
				)
			)
		)
		(duplicate_pad_numbers_are_jumpers no)
		(fp_circle
			(center 0 0)
			(end 0 2.4003)
			(stroke
				(width 0.1524)
				(type default)
			)
			(fill no)
			(layer "F.SilkS")
		)
		(fp_arc
			(start -6.015482 2.690876)
			(mid -2.409198 -6.133258)
			(end 6.23951 -2.124456)
			(stroke
				(width 0.1524)
				(type default)
			)
			(layer "B.SilkS")
		)
		(fp_circle
			(center 0 0)
			(end 0 6.5913)
			(stroke
				(width 0.1)
				(type default)
			)
			(fill no)
			(layer "B.Fab")
		)
		(fp_circle
			(center 0 0)
			(end 0 2.4003)
			(stroke
				(width 0.1)
				(type default)
			)
			(fill no)
			(layer "F.Fab")
		)
		(pad "" np_thru_hole circle
			(at 0 0 90)
			(size 3.175 3.175)
			(drill 3.175)
			(layers "*.Cu" "*.Mask")
			(clearance 0.381)
			(thermal_gap 0.381)
		)
		(zone
			(layers "F.Cu" "B.Cu" "In1.Cu" "In2.Cu" "In3.Cu" "In4.Cu" "In5.Cu" "In6.Cu"
				"In7.Cu" "In8.Cu" "In9.Cu" "In10.Cu"
			)
			(hatch none 0.5)
			(connect_pads
				(clearance 0)
			)
			(min_thickness 0.25)
			(keepout
				(tracks not_allowed)
				(vias allowed)
				(pads allowed)
				(copperpour not_allowed)
				(footprints allowed)
			)
			(placement
				(enabled no)
				(sheetname "")
			)
			(fill
				(thermal_gap 0.5)
				(thermal_bridge_width 0.5)
				(island_removal_mode 0)
			)
			(polygon
				(pts
					(arc
						(start 88.617806 -109.933486)
						(mid 84.426806 -109.933486)
						(end 88.617806 -109.933486)
					)
				)
			)
		)
	)
)
